#ISCELL
  pure_quanta quanta_title_block_c *
  *
#ISCELL
  standard offpage *
  page196_i1
#CELL
  pure_quanta q_res *
  page196_i10
#CELL
  pure_quanta q_res *
  page196_i11
#CELL
  pure_quanta q_res *
  page196_i12
#CELL
  pure_quanta q_res *
  page196_i13
#CELL
  pure_quanta q_res *
  page196_i14
#CELL
  pure_quanta q_res *
  page196_i15
#CELL
  pure_quanta q_res *
  page196_i16
#CELL
  pure_quanta q_res *
  page196_i17
#CELL
  pure_quanta q_res *
  page196_i18
#ISCELL
  standard offpage *
  page196_i19
#ISCELL
  standard offpage *
  page196_i2
#ISCELL
  standard offpage *
  page196_i20
#ISCELL
  standard offpage *
  page196_i21
#ISCELL
  standard offpage *
  page196_i22
#ISCELL
  standard offpage *
  page196_i23
#CELL
  pure_quanta q_res *
  page196_i24
#CELL
  pure_quanta q_res *
  page196_i25
#CELL
  pure_quanta q_res *
  page196_i26
#CELL
  pure_quanta q_res *
  page196_i27
#CELL
  pure_quanta q_res *
  page196_i28
#ISCELL
  standard offpage *
  page196_i29
#ISCELL
  standard offpage *
  page196_i3
#ISCELL
  standard offpage *
  page196_i30
#ISCELL
  standard offpage *
  page196_i31
#ISCELL
  standard offpage *
  page196_i32
#ISCELL
  standard offpage *
  page196_i33
#ISCELL
  standard offpage *
  page196_i34
#ISCELL
  standard offpage *
  page196_i35
#ISCELL
  standard offpage *
  page196_i36
#ISCELL
  standard offpage *
  page196_i37
#ISCELL
  standard offpage *
  page196_i38
#ISCELL
  standard offpage *
  page196_i39
#ISCELL
  standard offpage *
  page196_i4
#ISCELL
  standard offpage *
  page196_i40
#ISCELL
  standard offpage *
  page196_i41
#ISCELL
  standard offpage *
  page196_i42
#ISCELL
  standard offpage *
  page196_i5
#ISCELL
  standard offpage *
  page196_i6
#ISCELL
  standard offpage *
  page196_i7
#ISCELL
  standard offpage *
  page196_i8
#ISCELL
  standard offpage *
  page196_i9
